(kicad_pcb
	(version 20260206)
	(generator "pcbnew")
	(generator_version "10.0")
	(general
		(thickness 1.6)
		(legacy_teardrops no)
	)
	(paper "A4")
	(title_block
		(title "01162023_DA0F0TEBIF0_F0T_Expander_BD_F_brd_V02_OCP.brd")
		(comment 1 "Grand Teton / footprints 3487-3491 of 9728")
	)
	(layers
		(0 "F.Cu" signal "TOP")
		(4 "In1.Cu" signal "GND")
		(6 "In2.Cu" signal "VCC")
		(8 "In3.Cu" signal "VCC1")
		(10 "In4.Cu" signal "GND1")
		(12 "In5.Cu" signal "IN1")
		(14 "In6.Cu" signal "GND2")
		(16 "In7.Cu" signal "IN2")
		(18 "In8.Cu" signal "GND3")
		(20 "In9.Cu" signal "IN3")
		(22 "In10.Cu" signal "GND4")
		(24 "In11.Cu" signal "IN4")
		(26 "In12.Cu" signal "GND5")
		(28 "In13.Cu" signal "IN5")
		(30 "In14.Cu" signal "GND6")
		(32 "In15.Cu" signal "IN6")
		(34 "In16.Cu" signal "GND7")
		(2 "B.Cu" signal "BOTTOM")
		(9 "F.Adhes" user "F.Adhesive")
		(11 "B.Adhes" user "B.Adhesive")
		(13 "F.Paste" user "Package Geometry/Pastemask Top")
		(15 "B.Paste" user "Package Geometry/Pastemask Bottom")
		(5 "F.SilkS" user "Ref Des/Silkscreen Top")
		(7 "B.SilkS" user "Ref Des/Silkscreen Bottom")
		(1 "F.Mask" user "Board Geometry/Soldermask Top")
		(3 "B.Mask" user "Board Geometry/Soldermask Bottom")
		(17 "Dwgs.User" user "User.Drawings")
		(19 "Cmts.User" user "User.Comments")
		(21 "Eco1.User" user "User.Eco1")
		(23 "Eco2.User" user "User.Eco2")
		(25 "Edge.Cuts" user "Board Geometry/Outline")
		(27 "Margin" user)
		(31 "F.CrtYd" user "Package Geometry/Place Bound Top")
		(29 "B.CrtYd" user "Package Geometry/Place Bound Bottom")
		(35 "F.Fab" user "Ref Des/Assembly Top")
		(33 "B.Fab" user "Ref Des/Assembly Bottom")
	)
	(footprint ""
		(layer "F.Cu")
		(at 104.243632 -49.95291 180)
		(property "Reference" "R544"
			(at 0 0 180)
			(layer "F.SilkS")
			(hide yes)
			(effects
				(font
					(size 1.27 1.27)
				)
			)
		)
		(property "Value" ""
			(at 0 0 180)
			(layer "F.Fab")
			(effects
				(font
					(size 1.27 1.27)
				)
			)
		)
		(duplicate_pad_numbers_are_jumpers no)
		(fp_line
			(start 0.7874 0.4064)
			(end -0.7874 0.4064)
			(stroke
				(width 0.1524)
				(type default)
			)
			(layer "F.SilkS")
		)
		(fp_line
			(start 0.7874 -0.4064)
			(end 0.7874 0.4064)
			(stroke
				(width 0.1524)
				(type default)
			)
			(layer "F.SilkS")
		)
		(fp_line
			(start -0.7874 0.4064)
			(end -0.7874 -0.4064)
			(stroke
				(width 0.1524)
				(type default)
			)
			(layer "F.SilkS")
		)
		(fp_line
			(start -0.7874 -0.4064)
			(end 0.7874 -0.4064)
			(stroke
				(width 0.1524)
				(type default)
			)
			(layer "F.SilkS")
		)
		(fp_line
			(start 0.67945 0.3048)
			(end 0.120396 0.3048)
			(stroke
				(width 0.1)
				(type default)
			)
			(layer "F.Fab")
		)
		(fp_line
			(start 0.67945 -0.3048)
			(end 0.67945 0.3048)
			(stroke
				(width 0.1)
				(type default)
			)
			(layer "F.Fab")
		)
		(fp_line
			(start 0.12065 -0.2794)
			(end 0.12065 -0.3048)
			(stroke
				(width 0.1)
				(type default)
			)
			(layer "F.Fab")
		)
		(fp_line
			(start 0.12065 -0.3048)
			(end 0.67945 -0.3048)
			(stroke
				(width 0.1)
				(type default)
			)
			(layer "F.Fab")
		)
		(fp_line
			(start 0.120396 0.3048)
			(end 0.120396 0.2794)
			(stroke
				(width 0.1)
				(type default)
			)
			(layer "F.Fab")
		)
		(fp_line
			(start 0.120396 0.2794)
			(end -0.12065 0.2794)
			(stroke
				(width 0.1)
				(type default)
			)
			(layer "F.Fab")
		)
		(fp_line
			(start -0.12065 0.3048)
			(end -0.67945 0.3048)
			(stroke
				(width 0.1)
				(type default)
			)
			(layer "F.Fab")
		)
		(fp_line
			(start -0.12065 0.2794)
			(end -0.12065 0.3048)
			(stroke
				(width 0.1)
				(type default)
			)
			(layer "F.Fab")
		)
		(fp_line
			(start -0.12065 -0.2794)
			(end 0.12065 -0.2794)
			(stroke
				(width 0.1)
				(type default)
			)
			(layer "F.Fab")
		)
		(fp_line
			(start -0.12065 -0.305054)
			(end -0.12065 -0.2794)
			(stroke
				(width 0.1)
				(type default)
			)
			(layer "F.Fab")
		)
		(fp_line
			(start -0.67945 0.3048)
			(end -0.67945 -0.305054)
			(stroke
				(width 0.1)
				(type default)
			)
			(layer "F.Fab")
		)
		(fp_line
			(start -0.67945 -0.305054)
			(end -0.12065 -0.305054)
			(stroke
				(width 0.1)
				(type default)
			)
			(layer "F.Fab")
		)
		(pad "1" smd circle
			(at -0.40005 0 180)
			(size 0 0)
			(layers "F.Cu" "F.Mask" "F.Paste")
			(net "SMB_BIC_I2C6_MUX_SSD_0_7_ADC_R_SCL")
		)
		(pad "2" smd circle
			(at 0.40005 0 180)
			(size 0 0)
			(layers "F.Cu" "F.Mask" "F.Paste")
			(net "SMB_SSD3_ADC_SCL")
		)
	)
	(footprint ""
		(layer "F.Cu")
		(at 339.979 -234.061 90)
		(property "Reference" "R3596"
			(at 0 0 90)
			(layer "F.SilkS")
			(hide yes)
			(effects
				(font
					(size 1.27 1.27)
				)
			)
		)
		(property "Value" ""
			(at 0 0 90)
			(layer "F.Fab")
			(effects
				(font
					(size 1.27 1.27)
				)
			)
		)
		(duplicate_pad_numbers_are_jumpers no)
		(fp_line
			(start 0.7874 -0.4064)
			(end 0.7874 0.4064)
			(stroke
				(width 0.1524)
				(type default)
			)
			(layer "F.SilkS")
		)
		(fp_line
			(start -0.7874 -0.4064)
			(end 0.7874 -0.4064)
			(stroke
				(width 0.1524)
				(type default)
			)
			(layer "F.SilkS")
		)
		(fp_line
			(start 0.7874 0.4064)
			(end -0.7874 0.4064)
			(stroke
				(width 0.1524)
				(type default)
			)
			(layer "F.SilkS")
		)
		(fp_line
			(start -0.7874 0.4064)
			(end -0.7874 -0.4064)
			(stroke
				(width 0.1524)
				(type default)
			)
			(layer "F.SilkS")
		)
		(fp_line
			(start -0.12065 -0.305054)
			(end -0.12065 -0.2794)
			(stroke
				(width 0.1)
				(type default)
			)
			(layer "F.Fab")
		)
		(fp_line
			(start -0.67945 -0.305054)
			(end -0.12065 -0.305054)
			(stroke
				(width 0.1)
				(type default)
			)
			(layer "F.Fab")
		)
		(fp_line
			(start 0.67945 -0.3048)
			(end 0.67945 0.3048)
			(stroke
				(width 0.1)
				(type default)
			)
			(layer "F.Fab")
		)
		(fp_line
			(start 0.12065 -0.3048)
			(end 0.67945 -0.3048)
			(stroke
				(width 0.1)
				(type default)
			)
			(layer "F.Fab")
		)
		(fp_line
			(start 0.12065 -0.2794)
			(end 0.12065 -0.3048)
			(stroke
				(width 0.1)
				(type default)
			)
			(layer "F.Fab")
		)
		(fp_line
			(start -0.12065 -0.2794)
			(end 0.12065 -0.2794)
			(stroke
				(width 0.1)
				(type default)
			)
			(layer "F.Fab")
		)
		(fp_line
			(start 0.120396 0.2794)
			(end -0.12065 0.2794)
			(stroke
				(width 0.1)
				(type default)
			)
			(layer "F.Fab")
		)
		(fp_line
			(start -0.12065 0.2794)
			(end -0.12065 0.3048)
			(stroke
				(width 0.1)
				(type default)
			)
			(layer "F.Fab")
		)
		(fp_line
			(start 0.67945 0.3048)
			(end 0.120396 0.3048)
			(stroke
				(width 0.1)
				(type default)
			)
			(layer "F.Fab")
		)
		(fp_line
			(start 0.120396 0.3048)
			(end 0.120396 0.2794)
			(stroke
				(width 0.1)
				(type default)
			)
			(layer "F.Fab")
		)
		(fp_line
			(start -0.12065 0.3048)
			(end -0.67945 0.3048)
			(stroke
				(width 0.1)
				(type default)
			)
			(layer "F.Fab")
		)
		(fp_line
			(start -0.67945 0.3048)
			(end -0.67945 -0.305054)
			(stroke
				(width 0.1)
				(type default)
			)
			(layer "F.Fab")
		)
		(pad "1" smd circle
			(at -0.40005 0 90)
			(size 0 0)
			(layers "F.Cu" "F.Mask" "F.Paste")
			(net "SSD1_PWRDIS")
		)
		(pad "2" smd circle
			(at 0.40005 0 90)
			(size 0 0)
			(layers "F.Cu" "F.Mask" "F.Paste")
			(net "SSD1_PWRDIS_R")
		)
	)
	(footprint ""
		(layer "F.Cu")
		(at 361.89031 -259.147564 180)
		(property "Reference" "R840"
			(at 0 0 180)
			(layer "F.SilkS")
			(hide yes)
			(effects
				(font
					(size 1.27 1.27)
				)
			)
		)
		(property "Value" ""
			(at 0 0 180)
			(layer "F.Fab")
			(effects
				(font
					(size 1.27 1.27)
				)
			)
		)
		(duplicate_pad_numbers_are_jumpers no)
		(fp_line
			(start 0.7874 0.4064)
			(end -0.7874 0.4064)
			(stroke
				(width 0.1524)
				(type default)
			)
			(layer "F.SilkS")
		)
		(fp_line
			(start 0.7874 -0.4064)
			(end 0.7874 0.4064)
			(stroke
				(width 0.1524)
				(type default)
			)
			(layer "F.SilkS")
		)
		(fp_line
			(start -0.7874 0.4064)
			(end -0.7874 -0.4064)
			(stroke
				(width 0.1524)
				(type default)
			)
			(layer "F.SilkS")
		)
		(fp_line
			(start -0.7874 -0.4064)
			(end 0.7874 -0.4064)
			(stroke
				(width 0.1524)
				(type default)
			)
			(layer "F.SilkS")
		)
		(fp_line
			(start 0.67945 0.3048)
			(end 0.120396 0.3048)
			(stroke
				(width 0.1)
				(type default)
			)
			(layer "F.Fab")
		)
		(fp_line
			(start 0.67945 -0.3048)
			(end 0.67945 0.3048)
			(stroke
				(width 0.1)
				(type default)
			)
			(layer "F.Fab")
		)
		(fp_line
			(start 0.12065 -0.2794)
			(end 0.12065 -0.3048)
			(stroke
				(width 0.1)
				(type default)
			)
			(layer "F.Fab")
		)
		(fp_line
			(start 0.12065 -0.3048)
			(end 0.67945 -0.3048)
			(stroke
				(width 0.1)
				(type default)
			)
			(layer "F.Fab")
		)
		(fp_line
			(start 0.120396 0.3048)
			(end 0.120396 0.2794)
			(stroke
				(width 0.1)
				(type default)
			)
			(layer "F.Fab")
		)
		(fp_line
			(start 0.120396 0.2794)
			(end -0.12065 0.2794)
			(stroke
				(width 0.1)
				(type default)
			)
			(layer "F.Fab")
		)
		(fp_line
			(start -0.12065 0.3048)
			(end -0.67945 0.3048)
			(stroke
				(width 0.1)
				(type default)
			)
			(layer "F.Fab")
		)
		(fp_line
			(start -0.12065 0.2794)
			(end -0.12065 0.3048)
			(stroke
				(width 0.1)
				(type default)
			)
			(layer "F.Fab")
		)
		(fp_line
			(start -0.12065 -0.2794)
			(end 0.12065 -0.2794)
			(stroke
				(width 0.1)
				(type default)
			)
			(layer "F.Fab")
		)
		(fp_line
			(start -0.12065 -0.305054)
			(end -0.12065 -0.2794)
			(stroke
				(width 0.1)
				(type default)
			)
			(layer "F.Fab")
		)
		(fp_line
			(start -0.67945 0.3048)
			(end -0.67945 -0.305054)
			(stroke
				(width 0.1)
				(type default)
			)
			(layer "F.Fab")
		)
		(fp_line
			(start -0.67945 -0.305054)
			(end -0.12065 -0.305054)
			(stroke
				(width 0.1)
				(type default)
			)
			(layer "F.Fab")
		)
		(pad "1" smd circle
			(at -0.40005 0 180)
			(size 0 0)
			(layers "F.Cu" "F.Mask" "F.Paste")
			(net "PWRGD_P0V8_PEX3_R")
		)
		(pad "2" smd circle
			(at 0.40005 0 180)
			(size 0 0)
			(layers "F.Cu" "F.Mask" "F.Paste")
			(net "P0V8_PEX3_BVRRDY")
		)
	)
	(footprint ""
		(layer "F.Cu")
		(at 121.441972 -119.071136)
		(property "Reference" "PR6854"
			(at 0 0 0)
			(layer "F.SilkS")
			(hide yes)
			(effects
				(font
					(size 1.27 1.27)
				)
			)
		)
		(property "Value" ""
			(at 0 0 0)
			(layer "F.Fab")
			(effects
				(font
					(size 1.27 1.27)
				)
			)
		)
		(duplicate_pad_numbers_are_jumpers no)
		(fp_line
			(start -0.7874 -0.4064)
			(end 0.7874 -0.4064)
			(stroke
				(width 0.1524)
				(type default)
			)
			(layer "F.SilkS")
		)
		(fp_line
			(start -0.7874 0.4064)
			(end -0.7874 -0.4064)
			(stroke
				(width 0.1524)
				(type default)
			)
			(layer "F.SilkS")
		)
		(fp_line
			(start 0.7874 -0.4064)
			(end 0.7874 0.4064)
			(stroke
				(width 0.1524)
				(type default)
			)
			(layer "F.SilkS")
		)
		(fp_line
			(start 0.7874 0.4064)
			(end -0.7874 0.4064)
			(stroke
				(width 0.1524)
				(type default)
			)
			(layer "F.SilkS")
		)
		(fp_line
			(start -0.67945 -0.305054)
			(end -0.12065 -0.305054)
			(stroke
				(width 0.1)
				(type default)
			)
			(layer "F.Fab")
		)
		(fp_line
			(start -0.67945 0.3048)
			(end -0.67945 -0.305054)
			(stroke
				(width 0.1)
				(type default)
			)
			(layer "F.Fab")
		)
		(fp_line
			(start -0.12065 -0.305054)
			(end -0.12065 -0.2794)
			(stroke
				(width 0.1)
				(type default)
			)
			(layer "F.Fab")
		)
		(fp_line
			(start -0.12065 -0.2794)
			(end 0.12065 -0.2794)
			(stroke
				(width 0.1)
				(type default)
			)
			(layer "F.Fab")
		)
		(fp_line
			(start -0.12065 0.2794)
			(end -0.12065 0.3048)
			(stroke
				(width 0.1)
				(type default)
			)
			(layer "F.Fab")
		)
		(fp_line
			(start -0.12065 0.3048)
			(end -0.67945 0.3048)
			(stroke
				(width 0.1)
				(type default)
			)
			(layer "F.Fab")
		)
		(fp_line
			(start 0.120396 0.2794)
			(end -0.12065 0.2794)
			(stroke
				(width 0.1)
				(type default)
			)
			(layer "F.Fab")
		)
		(fp_line
			(start 0.120396 0.3048)
			(end 0.120396 0.2794)
			(stroke
				(width 0.1)
				(type default)
			)
			(layer "F.Fab")
		)
		(fp_line
			(start 0.12065 -0.3048)
			(end 0.67945 -0.3048)
			(stroke
				(width 0.1)
				(type default)
			)
			(layer "F.Fab")
		)
		(fp_line
			(start 0.12065 -0.2794)
			(end 0.12065 -0.3048)
			(stroke
				(width 0.1)
				(type default)
			)
			(layer "F.Fab")
		)
		(fp_line
			(start 0.67945 -0.3048)
			(end 0.67945 0.3048)
			(stroke
				(width 0.1)
				(type default)
			)
			(layer "F.Fab")
		)
		(fp_line
			(start 0.67945 0.3048)
			(end 0.120396 0.3048)
			(stroke
				(width 0.1)
				(type default)
			)
			(layer "F.Fab")
		)
		(pad "1" smd circle
			(at -0.40005 0)
			(size 0 0)
			(layers "F.Cu" "F.Mask" "F.Paste")
			(net "P3V3_CO_ILIMIT")
		)
		(pad "2" smd circle
			(at 0.40005 0)
			(size 0 0)
			(layers "F.Cu" "F.Mask" "F.Paste")
			(net "GND")
		)
	)
	(footprint ""
		(layer "F.Cu")
		(at 320.695828 -310.509412 135)
		(property "Reference" "R1372"
			(at 0 0 135)
			(layer "F.SilkS")
			(hide yes)
			(effects
				(font
					(size 1.27 1.27)
				)
			)
		)
		(property "Value" ""
			(at 0 0 135)
			(layer "F.Fab")
			(effects
				(font
					(size 1.27 1.27)
				)
			)
		)
		(duplicate_pad_numbers_are_jumpers no)
		(fp_line
			(start 0.787389 -0.406267)
			(end 0.787389 0.406267)
			(stroke
				(width 0.1524)
				(type default)
			)
			(layer "F.SilkS")
		)
		(fp_line
			(start 0.787389 0.406267)
			(end -0.787389 0.406267)
			(stroke
				(width 0.1524)
				(type default)
			)
			(layer "F.SilkS")
		)
		(fp_line
			(start -0.787389 -0.406267)
			(end 0.787389 -0.406267)
			(stroke
				(width 0.1524)
				(type default)
			)
			(layer "F.SilkS")
		)
		(fp_line
			(start -0.787389 0.406267)
			(end -0.787389 -0.406267)
			(stroke
				(width 0.1524)
				(type default)
			)
			(layer "F.SilkS")
		)
		(fp_line
			(start 0.679446 -0.30479)
			(end 0.679446 0.30479)
			(stroke
				(width 0.1)
				(type default)
			)
			(layer "F.Fab")
		)
		(fp_line
			(start 0.120515 -0.30479)
			(end 0.679446 -0.30479)
			(stroke
				(width 0.1)
				(type default)
			)
			(layer "F.Fab")
		)
		(fp_line
			(start 0.120695 -0.279466)
			(end 0.120515 -0.30479)
			(stroke
				(width 0.1)
				(type default)
			)
			(layer "F.Fab")
		)
		(fp_line
			(start 0.679446 0.30479)
			(end 0.120515 0.30479)
			(stroke
				(width 0.1)
				(type default)
			)
			(layer "F.Fab")
		)
		(fp_line
			(start -0.120695 -0.304969)
			(end -0.120695 -0.279466)
			(stroke
				(width 0.1)
				(type default)
			)
			(layer "F.Fab")
		)
		(fp_line
			(start -0.120695 -0.279466)
			(end 0.120695 -0.279466)
			(stroke
				(width 0.1)
				(type default)
			)
			(layer "F.Fab")
		)
		(fp_line
			(start 0.120335 0.279466)
			(end -0.120695 0.279466)
			(stroke
				(width 0.1)
				(type default)
			)
			(layer "F.Fab")
		)
		(fp_line
			(start 0.120515 0.30479)
			(end 0.120335 0.279466)
			(stroke
				(width 0.1)
				(type default)
			)
			(layer "F.Fab")
		)
		(fp_line
			(start -0.679446 -0.305149)
			(end -0.120695 -0.304969)
			(stroke
				(width 0.1)
				(type default)
			)
			(layer "F.Fab")
		)
		(fp_line
			(start -0.120695 0.279466)
			(end -0.120515 0.30479)
			(stroke
				(width 0.1)
				(type default)
			)
			(layer "F.Fab")
		)
		(fp_line
			(start -0.120515 0.30479)
			(end -0.679446 0.30479)
			(stroke
				(width 0.1)
				(type default)
			)
			(layer "F.Fab")
		)
		(fp_line
			(start -0.679446 0.30479)
			(end -0.679446 -0.305149)
			(stroke
				(width 0.1)
				(type default)
			)
			(layer "F.Fab")
		)
		(pad "1" smd circle
			(at -0.40005 0 135)
			(size 0 0)
			(layers "F.Cu" "F.Mask" "F.Paste")
			(net "PEX2_SPARE2")
		)
		(pad "2" smd circle
			(at 0.40005 0 135)
			(size 0 0)
			(layers "F.Cu" "F.Mask" "F.Paste")
			(net "P1V8_PEX")
		)
	)
)
